G04 ================== begin FILE IDENTIFICATION RECORD ==================*
G04 Layout Name:  14629-1a.brd*
G04 Film Name:    L1*
G04 File Format:  Gerber RS274X*
G04 File Origin:  Cadence Allegro 16.5-S037*
G04 Origin Date:  Tue Nov 25 11:50:48 2014*
G04 *
G04 Layer:  VIA CLASS/TOP*
G04 Layer:  PIN/TOP*
G04 Layer:  ETCH/TOP*
G04 Layer:  DRAWING FORMAT/LAYER_PCB_STORY*
G04 Layer:  DRAWING FORMAT/LAYER_L1*
G04 *
G04 Offset:    (0.00 0.00)*
G04 Mirror:    No*
G04 Mode:      Positive*
G04 Rotation:  0*
G04 FullContactRelief:  No*
G04 UndefLineWidth:     6.00*
G04 ================== end FILE IDENTIFICATION RECORD ====================*
%FSLAX35Y35*MOIN*%
%IR0*IPPOS*OFA0.00000B0.00000*MIA0B0*SFA1.00000B1.00000*%
%AMMACRO19*
4,1,40,.017,-.013,
.017,.013,
.016939,.013695,
.016759,.014368,
.016464,.015,
.016064,.015571,
.015571,.016064,
.015,.016464,
.014368,.016759,
.013695,.016939,
.013,.017,
-.013,.017,
-.013695,.016939,
-.014368,.016759,
-.015,.016464,
-.015571,.016064,
-.016064,.015571,
-.016464,.015,
-.016759,.014368,
-.016939,.013695,
-.017,.013,
-.017,-.013,
-.016939,-.013695,
-.016759,-.014368,
-.016464,-.015,
-.016064,-.015571,
-.015571,-.016064,
-.015,-.016464,
-.014368,-.016759,
-.013695,-.016939,
-.013,-.017,
.013,-.017,
.013695,-.016939,
.014368,-.016759,
.015,-.016464,
.015571,-.016064,
.016064,-.015571,
.016464,-.015,
.016759,-.014368,
.016939,-.013695,
.017,-.013,
0.0*
%
%ADD19MACRO19*%
%ADD36R,.11X.055*%
%ADD10C,.01*%
%ADD42R,.074X.122*%
%AMMACRO11*
4,1,21,.062,.1775,
.092823,.174803,
.122709,.166795,
.15075,.15372,
.176095,.135973,
.197973,.114095,
.21572,.08875,
.228795,.060709,
.236803,.030823,
.2395,0.0,
.236803,-.030823,
.228795,-.060709,
.21572,-.08875,
.197973,-.114095,
.176095,-.135973,
.15075,-.15372,
.122709,-.166795,
.092823,-.174803,
.062,-.1775,
-.2395,-.1775,
-.2395,.1775,
.062,.1775,
0.0*
%
%ADD11MACRO11*%
%ADD12C,.04*%
%ADD34C,.032*%
%ADD41C,.052*%
%ADD17R,.197X.032*%
%ADD40C,.064*%
%ADD13C,.028*%
%ADD38C,.057*%
%AMMACRO33*
4,1,40,.007,.011,
-.007,.011,
-.007695,.010939,
-.008368,.010759,
-.009,.010464,
-.009571,.010064,
-.010064,.009571,
-.010464,.009,
-.010759,.008368,
-.010939,.007695,
-.011,.007,
-.011,-.007,
-.010939,-.007695,
-.010759,-.008368,
-.010464,-.009,
-.010064,-.009571,
-.009571,-.010064,
-.009,-.010464,
-.008368,-.010759,
-.007695,-.010939,
-.007,-.011,
.007,-.011,
.007695,-.010939,
.008368,-.010759,
.009,-.010464,
.009571,-.010064,
.010064,-.009571,
.010464,-.009,
.010759,-.008368,
.010939,-.007695,
.011,-.007,
.011,.007,
.010939,.007695,
.010759,.008368,
.010464,.009,
.010064,.009571,
.009571,.010064,
.009,.010464,
.008368,.010759,
.007695,.010939,
.007,.011,
0.0*
%
%ADD33MACRO33*%
%AMMACRO30*
4,1,40,.011,-.007,
.011,.007,
.010939,.007695,
.010759,.008368,
.010464,.009,
.010064,.009571,
.009571,.010064,
.009,.010464,
.008368,.010759,
.007695,.010939,
.007,.011,
-.007,.011,
-.007695,.010939,
-.008368,.010759,
-.009,.010464,
-.009571,.010064,
-.010064,.009571,
-.010464,.009,
-.010759,.008368,
-.010939,.007695,
-.011,.007,
-.011,-.007,
-.010939,-.007695,
-.010759,-.008368,
-.010464,-.009,
-.010064,-.009571,
-.009571,-.010064,
-.009,-.010464,
-.008368,-.010759,
-.007695,-.010939,
-.007,-.011,
.007,-.011,
.007695,-.010939,
.008368,-.010759,
.009,-.010464,
.009571,-.010064,
.010064,-.009571,
.010464,-.009,
.010759,-.008368,
.010939,-.007695,
.011,-.007,
0.0*
%
%ADD30MACRO30*%
%AMMACRO27*
4,1,40,-.017,.013,
-.017,-.013,
-.016939,-.013695,
-.016759,-.014368,
-.016464,-.015,
-.016064,-.015571,
-.015571,-.016064,
-.015,-.016464,
-.014368,-.016759,
-.013695,-.016939,
-.013,-.017,
.013,-.017,
.013695,-.016939,
.014368,-.016759,
.015,-.016464,
.015571,-.016064,
.016064,-.015571,
.016464,-.015,
.016759,-.014368,
.016939,-.013695,
.017,-.013,
.017,.013,
.016939,.013695,
.016759,.014368,
.016464,.015,
.016064,.015571,
.015571,.016064,
.015,.016464,
.014368,.016759,
.013695,.016939,
.013,.017,
-.013,.017,
-.013695,.016939,
-.014368,.016759,
-.015,.016464,
-.015571,.016064,
-.016064,.015571,
-.016464,.015,
-.016759,.014368,
-.016939,.013695,
-.017,.013,
0.0*
%
%ADD27MACRO27*%
%AMMACRO32*
4,1,40,.007,.011,
-.007,.011,
-.007695,.010939,
-.008368,.010759,
-.009,.010464,
-.009571,.010064,
-.010064,.009571,
-.010464,.009,
-.010759,.008368,
-.010939,.007695,
-.011,.007,
-.011,-.007,
-.010939,-.007695,
-.010759,-.008368,
-.010464,-.009,
-.010064,-.009571,
-.009571,-.010064,
-.009,-.010464,
-.008368,-.010759,
-.007695,-.010939,
-.007,-.011,
.007,-.011,
.007695,-.010939,
.008368,-.010759,
.009,-.010464,
.009571,-.010064,
.010064,-.009571,
.010464,-.009,
.010759,-.008368,
.010939,-.007695,
.011,-.007,
.011,.007,
.010939,.007695,
.010759,.008368,
.010464,.009,
.010064,.009571,
.009571,.010064,
.009,.010464,
.008368,.010759,
.007695,.010939,
.007,.011,
0.0*
%
%ADD32MACRO32*%
%AMMACRO23*
4,1,40,.011,-.007,
.011,.007,
.010939,.007695,
.010759,.008368,
.010464,.009,
.010064,.009571,
.009571,.010064,
.009,.010464,
.008368,.010759,
.007695,.010939,
.007,.011,
-.007,.011,
-.007695,.010939,
-.008368,.010759,
-.009,.010464,
-.009571,.010064,
-.010064,.009571,
-.010464,.009,
-.010759,.008368,
-.010939,.007695,
-.011,.007,
-.011,-.007,
-.010939,-.007695,
-.010759,-.008368,
-.010464,-.009,
-.010064,-.009571,
-.009571,-.010064,
-.009,-.010464,
-.008368,-.010759,
-.007695,-.010939,
-.007,-.011,
.007,-.011,
.007695,-.010939,
.008368,-.010759,
.009,-.010464,
.009571,-.010064,
.010064,-.009571,
.010464,-.009,
.010759,-.008368,
.010939,-.007695,
.011,-.007,
0.0*
%
%ADD23MACRO23*%
%AMMACRO20*
4,1,40,-.017,.013,
-.017,-.013,
-.016939,-.013695,
-.016759,-.014368,
-.016464,-.015,
-.016064,-.015571,
-.015571,-.016064,
-.015,-.016464,
-.014368,-.016759,
-.013695,-.016939,
-.013,-.017,
.013,-.017,
.013695,-.016939,
.014368,-.016759,
.015,-.016464,
.015571,-.016064,
.016064,-.015571,
.016464,-.015,
.016759,-.014368,
.016939,-.013695,
.017,-.013,
.017,.013,
.016939,.013695,
.016759,.014368,
.016464,.015,
.016064,.015571,
.015571,.016064,
.015,.016464,
.014368,.016759,
.013695,.016939,
.013,.017,
-.013,.017,
-.013695,.016939,
-.014368,.016759,
-.015,.016464,
-.015571,.016064,
-.016064,.015571,
-.016464,.015,
-.016759,.014368,
-.016939,.013695,
-.017,.013,
0.0*
%
%ADD20MACRO20*%
%ADD15R,.001X.001*%
%ADD25R,.016X.06*%
%ADD16R,.055X.045*%
%ADD18R,.248X.165*%
%ADD14R,.248X.372*%
%ADD35O,.827X.355*%
%AMMACRO39*
4,1,40,.007,.0225,
.008389,.022378,
.009736,.022018,
.011,.021428,
.012142,.020628,
.013128,.019642,
.013928,.0185,
.014518,.017236,
.014878,.015889,
.015,.0145,
.015,-.0145,
.014878,-.015889,
.014518,-.017236,
.013928,-.0185,
.013128,-.019642,
.012142,-.020628,
.011,-.021428,
.009736,-.022018,
.008389,-.022378,
.007,-.0225,
-.007,-.0225,
-.008389,-.022378,
-.009736,-.022018,
-.011,-.021428,
-.012142,-.020628,
-.013128,-.019642,
-.013928,-.0185,
-.014518,-.017236,
-.014878,-.015889,
-.015,-.0145,
-.015,.0145,
-.014878,.015889,
-.014518,.017236,
-.013928,.0185,
-.013128,.019642,
-.012142,.020628,
-.011,.021428,
-.009736,.022018,
-.008389,.022378,
-.007,.0225,
.007,.0225,
0.0*
%
%ADD39MACRO39*%
%ADD37R,.095X.09*%
%AMMACRO31*
4,1,40,-.008,-.012,
.008,-.012,
.008695,-.011939,
.009368,-.011759,
.01,-.011464,
.010571,-.011064,
.011064,-.010571,
.011464,-.01,
.011759,-.009368,
.011939,-.008695,
.012,-.008,
.012,.008,
.011939,.008695,
.011759,.009368,
.011464,.01,
.011064,.010571,
.010571,.011064,
.01,.011464,
.009368,.011759,
.008695,.011939,
.008,.012,
-.008,.012,
-.008695,.011939,
-.009368,.011759,
-.01,.011464,
-.010571,.011064,
-.011064,.010571,
-.011464,.01,
-.011759,.009368,
-.011939,.008695,
-.012,.008,
-.012,-.008,
-.011939,-.008695,
-.011759,-.009368,
-.011464,-.01,
-.011064,-.010571,
-.010571,-.011064,
-.01,-.011464,
-.009368,-.011759,
-.008695,-.011939,
-.008,-.012,
0.0*
%
%ADD31MACRO31*%
%AMMACRO29*
4,1,40,-.007,-.011,
.007,-.011,
.007695,-.010939,
.008368,-.010759,
.009,-.010464,
.009571,-.010064,
.010064,-.009571,
.010464,-.009,
.010759,-.008368,
.010939,-.007695,
.011,-.007,
.011,.007,
.010939,.007695,
.010759,.008368,
.010464,.009,
.010064,.009571,
.009571,.010064,
.009,.010464,
.008368,.010759,
.007695,.010939,
.007,.011,
-.007,.011,
-.007695,.010939,
-.008368,.010759,
-.009,.010464,
-.009571,.010064,
-.010064,.009571,
-.010464,.009,
-.010759,.008368,
-.010939,.007695,
-.011,.007,
-.011,-.007,
-.010939,-.007695,
-.010759,-.008368,
-.010464,-.009,
-.010064,-.009571,
-.009571,-.010064,
-.009,-.010464,
-.008368,-.010759,
-.007695,-.010939,
-.007,-.011,
0.0*
%
%ADD29MACRO29*%
%AMMACRO28*
4,1,40,-.011,.007,
-.011,-.007,
-.010939,-.007695,
-.010759,-.008368,
-.010464,-.009,
-.010064,-.009571,
-.009571,-.010064,
-.009,-.010464,
-.008368,-.010759,
-.007695,-.010939,
-.007,-.011,
.007,-.011,
.007695,-.010939,
.008368,-.010759,
.009,-.010464,
.009571,-.010064,
.010064,-.009571,
.010464,-.009,
.010759,-.008368,
.010939,-.007695,
.011,-.007,
.011,.007,
.010939,.007695,
.010759,.008368,
.010464,.009,
.010064,.009571,
.009571,.010064,
.009,.010464,
.008368,.010759,
.007695,.010939,
.007,.011,
-.007,.011,
-.007695,.010939,
-.008368,.010759,
-.009,.010464,
-.009571,.010064,
-.010064,.009571,
-.010464,.009,
-.010759,.008368,
-.010939,.007695,
-.011,.007,
0.0*
%
%ADD28MACRO28*%
%AMMACRO26*
4,1,40,.017,-.013,
.017,.013,
.016939,.013695,
.016759,.014368,
.016464,.015,
.016064,.015571,
.015571,.016064,
.015,.016464,
.014368,.016759,
.013695,.016939,
.013,.017,
-.013,.017,
-.013695,.016939,
-.014368,.016759,
-.015,.016464,
-.015571,.016064,
-.016064,.015571,
-.016464,.015,
-.016759,.014368,
-.016939,.013695,
-.017,.013,
-.017,-.013,
-.016939,-.013695,
-.016759,-.014368,
-.016464,-.015,
-.016064,-.015571,
-.015571,-.016064,
-.015,-.016464,
-.014368,-.016759,
-.013695,-.016939,
-.013,-.017,
.013,-.017,
.013695,-.016939,
.014368,-.016759,
.015,-.016464,
.015571,-.016064,
.016064,-.015571,
.016464,-.015,
.016759,-.014368,
.016939,-.013695,
.017,-.013,
0.0*
%
%ADD26MACRO26*%
%AMMACRO22*
4,1,40,-.007,-.011,
.007,-.011,
.007695,-.010939,
.008368,-.010759,
.009,-.010464,
.009571,-.010064,
.010064,-.009571,
.010464,-.009,
.010759,-.008368,
.010939,-.007695,
.011,-.007,
.011,.007,
.010939,.007695,
.010759,.008368,
.010464,.009,
.010064,.009571,
.009571,.010064,
.009,.010464,
.008368,.010759,
.007695,.010939,
.007,.011,
-.007,.011,
-.007695,.010939,
-.008368,.010759,
-.009,.010464,
-.009571,.010064,
-.010064,.009571,
-.010464,.009,
-.010759,.008368,
-.010939,.007695,
-.011,.007,
-.011,-.007,
-.010939,-.007695,
-.010759,-.008368,
-.010464,-.009,
-.010064,-.009571,
-.009571,-.010064,
-.009,-.010464,
-.008368,-.010759,
-.007695,-.010939,
-.007,-.011,
0.0*
%
%ADD22MACRO22*%
%AMMACRO21*
4,1,40,-.008,-.012,
.008,-.012,
.008695,-.011939,
.009368,-.011759,
.01,-.011464,
.010571,-.011064,
.011064,-.010571,
.011464,-.01,
.011759,-.009368,
.011939,-.008695,
.012,-.008,
.012,.008,
.011939,.008695,
.011759,.009368,
.011464,.01,
.011064,.010571,
.010571,.011064,
.01,.011464,
.009368,.011759,
.008695,.011939,
.008,.012,
-.008,.012,
-.008695,.011939,
-.009368,.011759,
-.01,.011464,
-.010571,.011064,
-.011064,.010571,
-.011464,.01,
-.011759,.009368,
-.011939,.008695,
-.012,.008,
-.012,-.008,
-.011939,-.008695,
-.011759,-.009368,
-.011464,-.01,
-.011064,-.010571,
-.010571,-.011064,
-.01,-.011464,
-.009368,-.011759,
-.008695,-.011939,
-.008,-.012,
0.0*
%
%ADD21MACRO21*%
%AMMACRO24*
4,1,40,-.011,.007,
-.011,-.007,
-.010939,-.007695,
-.010759,-.008368,
-.010464,-.009,
-.010064,-.009571,
-.009571,-.010064,
-.009,-.010464,
-.008368,-.010759,
-.007695,-.010939,
-.007,-.011,
.007,-.011,
.007695,-.010939,
.008368,-.010759,
.009,-.010464,
.009571,-.010064,
.010064,-.009571,
.010464,-.009,
.010759,-.008368,
.010939,-.007695,
.011,-.007,
.011,.007,
.010939,.007695,
.010759,.008368,
.010464,.009,
.010064,.009571,
.009571,.010064,
.009,.010464,
.008368,.010759,
.007695,.010939,
.007,.011,
-.007,.011,
-.007695,.010939,
-.008368,.010759,
-.009,.010464,
-.009571,.010064,
-.010064,.009571,
-.010464,.009,
-.010759,.008368,
-.010939,.007695,
-.011,.007,
0.0*
%
%ADD24MACRO24*%
%ADD43C,.02*%
%ADD44C,.03*%
%ADD45C,.014*%
%ADD46C,.015*%
%ADD47C,.006*%
%ADD48C,.0055*%
%ADD49C,.08104*%
%ADD54R,.015X.015*%
%ADD55C,.18204*%
%ADD53R,.0252X.03564*%
%ADD51R,.02814X.03564*%
%ADD52R,.0494X.03564*%
%ADD50R,.03366X.02618*%
G75*
%LPD*%
G75*
G36*
G01X624773Y68500D02*
X626297Y70024D01*
X629112D01*
X631594D01*
X632554Y69064D01*
X636443D01*
X636686Y69307D01*
G02X637369Y69024I283J-283D01*
G01Y4080D01*
X636492Y3203D01*
X4381D01*
X3000Y4584D01*
Y77000D01*
X5500Y79500D01*
X37000D01*
X54000Y62500D01*
X548000D01*
X581000Y95500D01*
X607500D01*
X613000Y90000D01*
Y73000D01*
X614500Y71500D01*
Y69000D01*
X615000Y68500D01*
X624773D01*
G37*
G36*
G01X416064Y184936D02*
X554436D01*
X554500Y185000D01*
X556000D01*
X568000Y197000D01*
X605500D01*
X608000Y194500D01*
Y162000D01*
X589000Y143000D01*
Y111500D01*
X592000Y108500D01*
X611000D01*
X622000Y97500D01*
Y76000D01*
X621500Y75500D01*
X615500D01*
X615000Y76000D01*
Y91500D01*
X608500Y98000D01*
X580500D01*
X546936Y64436D01*
X56500D01*
X37936Y83000D01*
X5500D01*
X3000Y85500D01*
Y110834D01*
X-921Y114755D01*
X-30850D01*
X-30866Y114772D01*
X-32938D01*
X-33302Y115136D01*
Y151236D01*
X-32642Y151896D01*
X-12594D01*
X-12326Y152164D01*
Y154539D01*
X-12645Y154858D01*
X-33024D01*
X-33302Y155136D01*
Y191436D01*
X-32778Y191960D01*
X409040D01*
X416064Y184936D01*
G37*
G36*
G01X417564Y187936D02*
X410564Y194936D01*
X-32902D01*
X-33302Y195336D01*
Y231336D01*
X-32702Y231936D01*
X-12538D01*
X-12366Y232108D01*
Y234653D01*
X-12575Y234862D01*
X-32628D01*
X-33202Y235436D01*
Y271336D01*
X-32609Y271929D01*
X-12610D01*
X-12463Y272076D01*
Y274708D01*
X-12616Y274861D01*
X-32727D01*
X-33202Y275336D01*
Y288382D01*
X-32585Y288999D01*
X814D01*
X22251Y310436D01*
X96398D01*
X110285Y296549D01*
X466021D01*
X532054Y230516D01*
X534338D01*
X534340Y230514D01*
X544000D01*
Y230500D01*
X553500D01*
X562000Y222000D01*
Y196000D01*
X553936Y187936D01*
X417564D01*
G37*
G36*
G01X-1002Y314209D02*
X-9525Y305686D01*
X-31054D01*
X-31296Y305928D01*
Y308663D01*
X-31198Y308761D01*
X-30956D01*
X-30955Y308760D01*
X-17679D01*
X-17599Y308840D01*
Y310498D01*
X-17704Y310603D01*
X-31124D01*
X-31296Y310775D01*
Y313350D01*
X-31002Y313644D01*
X-17783D01*
X-17782Y313643D01*
X-11903D01*
X-7286Y318260D01*
X-1770D01*
X-1002Y317492D01*
Y314209D01*
G37*
G36*
G01X605131Y291780D02*
X609674Y287238D01*
Y271792D01*
G02X608991Y271509I-400J0D01*
G01X605500Y275000D01*
X557000D01*
X555500Y273500D01*
X535115D01*
X479241Y329374D01*
X140292D01*
X94980Y374686D01*
X82778D01*
G03X82276Y375054I-1778J-1900D01*
G01X82252Y375067D01*
X74259Y383060D01*
Y391741D01*
X68564Y397436D01*
X49898D01*
X47898Y395436D01*
Y391936D01*
X47398Y391436D01*
X43898D01*
X42774Y390312D01*
X34714D01*
X33991Y389589D01*
Y385309D01*
X35514Y383786D01*
X39327D01*
X39803Y383310D01*
Y378360D01*
X39111Y377668D01*
X34113D01*
X29963Y381818D01*
X26153D01*
X24676Y380340D01*
Y374973D01*
X17105Y367402D01*
X17110Y367397D01*
Y363523D01*
X-572Y345841D01*
X-7430D01*
X-10102Y348513D01*
Y361936D01*
X-9602Y362436D01*
X-1102D01*
X3398Y366936D01*
Y467936D01*
X4898Y469436D01*
X635898D01*
X637261Y468073D01*
Y388090D01*
X633197Y385366D01*
X629500D01*
X628000Y386866D01*
Y404500D01*
X623750Y408750D01*
Y415750D01*
X621500Y418000D01*
X609000D01*
X606898Y415898D01*
Y397936D01*
X604398Y395436D01*
X532798D01*
X523798Y386436D01*
Y338998D01*
X523789Y338968D01*
G03X523685Y338484I2480J-786D01*
G01X523677Y338415D01*
X518131Y332869D01*
Y332077D01*
X518114Y332039D01*
G03X518131Y329924I2386J-1038D01*
G01Y308869D01*
X526000Y301000D01*
Y291500D01*
X526463Y291037D01*
X526478Y291002D01*
G03X527506Y289974I1833J805D01*
G01X527541Y289959D01*
X528000Y289500D01*
X538500D01*
X540780Y291780D01*
X605131D01*
G37*
G36*
G01X46931Y336500D02*
X42445Y340986D01*
X20614D01*
X17293Y344307D01*
Y351626D01*
X24243Y358576D01*
X29901D01*
X32545Y361220D01*
Y363711D01*
X33729Y364895D01*
X39665D01*
X40289Y364271D01*
Y352705D01*
X40603Y352391D01*
Y352390D01*
X47059Y345934D01*
X47987D01*
X48000Y345932D01*
G03X48650I325J2582D01*
G01X48663Y345934D01*
X58809D01*
X60500Y347625D01*
Y360500D01*
X61000Y361000D01*
X63000D01*
X63425Y360575D01*
Y358290D01*
X64469Y357246D01*
X67848D01*
X69075Y358473D01*
Y360313D01*
X70262Y361500D01*
X97000D01*
X119875Y338625D01*
Y337226D01*
X119149Y336500D01*
X46931D01*
G37*
G36*
G01X631099Y348121D02*
X637369Y343929D01*
Y321500D01*
X636369Y320500D01*
X622000D01*
X617500Y316000D01*
Y133000D01*
X621500Y129000D01*
X635500D01*
X637369Y127131D01*
Y75035D01*
G02X636686Y74752I-400J0D01*
G01X636474Y74964D01*
X632430D01*
X630966Y73500D01*
X626000D01*
X624000Y75500D01*
Y98000D01*
X611500Y110500D01*
X595000D01*
X593500Y112000D01*
Y130282D01*
G02X594187Y130561I400J0D01*
G03X598859Y145821I6522J6348D01*
G02X598495Y146495I-81J391D01*
G01X613000Y161000D01*
Y267500D01*
X612626Y267874D01*
Y288462D01*
X606355Y294734D01*
X540750D01*
Y300250D01*
X546500Y306000D01*
Y313902D01*
G03Y314098I-2600J98D01*
G01Y323000D01*
X548500Y325000D01*
X614000D01*
X614064Y324936D01*
X621898D01*
X627398Y330436D01*
Y347353D01*
X628166Y348121D01*
X631099D01*
G37*
G36*
G01X548264Y328236D02*
X547500Y329000D01*
Y334500D01*
X548000Y335000D01*
X594778D01*
X594804Y334993D01*
G03X596196I696J2507D01*
G01X596222Y335000D01*
X599278D01*
X599304Y334993D01*
G03X600696I696J2507D01*
G01X600722Y335000D01*
X612000D01*
X613598Y336598D01*
Y350436D01*
X613896Y350734D01*
X624300D01*
X624598Y350436D01*
Y331736D01*
X621098Y328236D01*
X548264D01*
G37*
G36*
G01X530932Y337202D02*
X528147Y339987D01*
X528146Y339988D01*
G03X528073Y340061I-1876J-1803D01*
G01X528072Y340062D01*
X527798Y340336D01*
Y384936D01*
X534398Y391536D01*
X609598D01*
X610098Y391036D01*
Y381686D01*
X596348D01*
X594598Y383436D01*
X540598D01*
X536298Y379136D01*
Y334500D01*
X535365Y333567D01*
X533000D01*
X532500Y334067D01*
Y335500D01*
X532439Y335561D01*
X532437Y335641D01*
G03X531002Y337195I-1601J-39D01*
G01X530932Y337202D01*
G37*
G36*
G01X610198Y350436D02*
X611598Y349036D01*
Y339000D01*
X609348Y336750D01*
X593712D01*
X592462Y338000D01*
Y348962D01*
X593936Y350436D01*
X610198D01*
G37*
G36*
G01X626500Y401500D02*
Y383500D01*
X625000Y382000D01*
X615000D01*
X614500Y382500D01*
Y393500D01*
X610500Y397500D01*
Y404000D01*
X611500Y405000D01*
X623000D01*
X626500Y401500D01*
G37*
%LPC*%
G75*
G36*
G01X25118Y253002D02*
G02X32056Y246063I0J-6938D01*
G01Y226378D01*
G02X25118Y219440I-6938J0D01*
G01X21181D01*
G02X14242Y226378I0J6939D01*
G01Y246063D01*
G02X21181Y253002I6939J0D01*
G01X25118D01*
G37*
G36*
G01X567981Y435774D02*
X558862D01*
X550912Y427824D01*
X550101D01*
G02X548700Y426998I-1401J775D01*
G01X547300D01*
G02X545928Y427774I0J1601D01*
G01X542362D01*
X492516Y377927D01*
Y376427D01*
X492061Y375973D01*
X492075Y375873D01*
G02X487766Y373560I-2575J-373D01*
G03X487234I-266J-299D01*
G02X485873Y378075I-1734J1940D01*
G01X485973Y378061D01*
X542138Y434226D01*
X545928D01*
G02X547300Y435002I1372J-825D01*
G01X548700D01*
G02X550072Y434226I0J-1601D01*
G01X550638D01*
X556888Y440476D01*
X560362D01*
Y444008D01*
X565502D01*
Y440476D01*
X582489D01*
X587589Y435376D01*
G03X588187Y435413I283J283D01*
G02X587678Y431594I2995J-2343D01*
G01X587194D01*
X585807Y432982D01*
G03X585126Y432734I-283J-283D01*
G02X577772Y434386I-3787J337D01*
G01X577816Y434506D01*
X576548Y435774D01*
X575011D01*
G03X574676Y435154I0J-400D01*
G02X572972Y429567I-3180J-2083D01*
G01Y423884D01*
X566612Y417524D01*
X549801D01*
G02X548400Y416698I-1401J775D01*
G01X547000D01*
G02X545398Y418300I0J1602D01*
G01Y419700D01*
G02X547000Y421302I1602J0D01*
G01X548400D01*
G02X549801Y420476I0J-1601D01*
G01X565388D01*
X570020Y425108D01*
Y429567D01*
G02X568316Y435154I1476J3504D01*
G03X567981Y435774I-335J220D01*
G37*
G54D49*
X570709Y161889D03*
X580709D03*
X570709Y191889D03*
X580709D03*
X570709Y181889D03*
X580709D03*
X570709Y171889D03*
X580709D03*
X590709Y161889D03*
X600709D03*
X590709Y191889D03*
X600709D03*
X590709Y181889D03*
X600709D03*
X590709Y171889D03*
X600709D03*
G54D54*
X539750Y277250D03*
X544750D03*
X39250Y393250D03*
X43250Y396250D03*
X542250Y417250D03*
Y420750D03*
G54D55*
X600709Y311909D03*
G54D53*
X599322Y442226D03*
G54D51*
X564095Y423916D03*
G54D52*
X600532D03*
G54D50*
X559489Y432067D03*
%LPD*%
G75*
G54D10*
X-23621Y15748D03*
Y937008D03*
X600709Y136909D03*
Y311909D03*
X1312285Y15747D03*
X1312281Y889328D03*
G54D20*
X38109Y368733D03*
X542500Y263771D03*
X618000Y77300D03*
X617798Y408736D03*
X612798Y408636D03*
G54D11*
X23957Y61023D03*
Y415354D03*
G54D21*
X41309Y387463D03*
G54D30*
X52705Y355795D03*
X48325Y355850D03*
X57398Y355860D03*
G54D12*
G01X2334Y318654D02*
Y313017D01*
X-8481Y302202D01*
X-12610D01*
X-23622Y62794D03*
Y916269D03*
X1297695Y58466D03*
G54D22*
X35198Y333436D03*
Y337936D03*
X30108Y368932D03*
Y374132D03*
X66098Y369470D03*
X66147Y373979D03*
X66150Y378236D03*
X534333Y268971D03*
Y263971D03*
X530236Y322102D03*
X530136Y330602D03*
X530236Y326402D03*
X522800Y326000D03*
G54D31*
X41309Y391063D03*
G54D13*
X6419Y116482D03*
X-3350Y117504D03*
X6419Y126482D03*
X-3581D03*
X6419Y136482D03*
X-3581D03*
X6419Y146482D03*
X-3581D03*
X6419Y156482D03*
X-3581D03*
X-2602Y206936D03*
X7398D03*
X-2602Y216936D03*
X7398D03*
X6419Y166482D03*
X-3581D03*
Y176482D03*
X6419D03*
X-2602Y226936D03*
X7398D03*
X-2602Y246936D03*
X7398D03*
X-2602Y236936D03*
X7398D03*
Y256936D03*
X-2602D03*
Y266936D03*
X7398D03*
Y276936D03*
X-2602D03*
X7398Y286936D03*
X3398Y326936D03*
X-2948Y302202D03*
X-2602Y316436D03*
X-7102Y327202D03*
X-6940Y316247D03*
X2334Y318654D03*
X1494Y343705D03*
X5694D03*
X-6602Y347202D03*
X-7102Y337202D03*
X-6602Y357202D03*
X6898Y387436D03*
X6398Y369936D03*
X6898Y445436D03*
Y465436D03*
X16419Y6482D03*
Y26482D03*
X36419Y6482D03*
Y26482D03*
X56419Y46482D03*
X16419Y86482D03*
X36419D03*
X56419Y66482D03*
Y86482D03*
X26419Y116482D03*
X16419D03*
X26419Y126482D03*
X16419D03*
X26419Y136482D03*
X16419D03*
X26419Y146482D03*
X16419D03*
X26419Y156482D03*
X16419D03*
X36419Y126482D03*
X16419Y106482D03*
X36419D03*
Y146482D03*
X56419Y126482D03*
Y106482D03*
Y146482D03*
X27398Y206936D03*
X17398D03*
X27398Y216936D03*
X17398D03*
X26419Y186482D03*
X16419D03*
X26419Y166482D03*
X16419D03*
Y176482D03*
X26419D03*
X36419Y186482D03*
Y166482D03*
X56419Y186482D03*
Y166482D03*
X57398Y206936D03*
X37398D03*
X17398Y256936D03*
X27398D03*
Y266936D03*
X17398D03*
X57398Y226936D03*
X36769D03*
X57398Y246936D03*
Y266936D03*
X36769Y246936D03*
X37398Y266936D03*
X17398Y276936D03*
X27398Y286936D03*
X17398D03*
X27398Y276936D03*
X10000Y332000D03*
X57398Y286936D03*
X37398D03*
X64398Y304436D03*
X30923Y335665D03*
X25500Y353000D03*
X25000Y343000D03*
X33986Y362933D03*
X26723Y335665D03*
X22000Y374500D03*
X34898Y344936D03*
X57398Y348682D03*
X52705Y348626D03*
X48325Y348514D03*
X62398Y338436D03*
X37500Y386500D03*
X22000Y387500D03*
X61898Y358936D03*
X43038Y353675D03*
X28182Y364061D03*
Y379003D03*
X43072Y360525D03*
X43159Y382607D03*
X62000Y442500D03*
X60052Y394674D03*
X35830Y442464D03*
X55352Y394674D03*
X51094Y394478D03*
X55500Y417000D03*
X19898Y465436D03*
X39898D03*
X76419Y46482D03*
X116419D03*
X96419D03*
X76419Y66482D03*
Y86482D03*
X116419Y66482D03*
X96419D03*
X116419Y86482D03*
X96419D03*
X76419Y126482D03*
Y106482D03*
Y146482D03*
X116419Y126482D03*
Y106482D03*
X96419Y126482D03*
Y106482D03*
X116419Y146482D03*
X96419D03*
X76419Y186482D03*
Y166482D03*
X77398Y206936D03*
X116419Y186482D03*
Y166482D03*
X96419Y186482D03*
Y166482D03*
X117398Y206936D03*
X97398D03*
X77398Y226936D03*
Y246936D03*
Y266936D03*
X117398Y226936D03*
X97398D03*
X117398Y246936D03*
X97398D03*
Y266936D03*
X116398D03*
X77398Y286936D03*
X86398Y303936D03*
X97398Y286936D03*
X116398D03*
X77898Y338436D03*
X78398Y358436D03*
X115330Y337964D03*
X96398Y337936D03*
X115330Y377964D03*
Y357964D03*
X95330Y377964D03*
Y357964D03*
X74803Y369471D03*
X81000Y372786D03*
X66041Y359891D03*
X66100Y383508D03*
X105330Y442964D03*
X85330D03*
X75500Y417500D03*
X115330Y417964D03*
X95330D03*
X91500Y465500D03*
X117500D03*
X67830Y465464D03*
X136419Y6482D03*
Y46482D03*
X176419Y6482D03*
Y26482D03*
X156419Y6482D03*
Y26482D03*
X176419Y46482D03*
X156419D03*
X136419Y66482D03*
Y86482D03*
X176419Y66482D03*
X156419D03*
X176419Y86482D03*
X156419D03*
X136419Y126482D03*
Y106482D03*
Y146482D03*
X176419Y126482D03*
Y106482D03*
X156419Y126482D03*
Y106482D03*
X176419Y146482D03*
X156419D03*
X136419Y186482D03*
Y166482D03*
X137398Y206936D03*
X176419Y186482D03*
Y166482D03*
X156419Y186482D03*
Y166482D03*
X177398Y206436D03*
X157398Y206936D03*
X137398Y226936D03*
Y246936D03*
Y266936D03*
X177398Y226936D03*
X157398D03*
X177398Y246936D03*
Y266936D03*
X157398Y246936D03*
Y266936D03*
X137398Y286936D03*
X177398D03*
X157398D03*
X135063Y304219D03*
X176762Y319444D03*
X135330Y337964D03*
Y377964D03*
Y357964D03*
X175330Y337964D03*
X155330D03*
X175330Y377964D03*
Y357964D03*
X155330Y377964D03*
Y357964D03*
X132000Y442500D03*
X135330Y417964D03*
X175500Y442000D03*
X175330Y417964D03*
X155000Y442000D03*
X155330Y417964D03*
X139898Y465436D03*
X159898D03*
X196419Y6482D03*
Y26482D03*
Y46482D03*
X236419Y6482D03*
Y26482D03*
X216419Y6482D03*
Y26482D03*
X236419Y46482D03*
X216419D03*
X196419Y66482D03*
Y86482D03*
X236419Y66482D03*
X216419D03*
X236419Y86482D03*
X216419D03*
X196419Y126482D03*
Y106482D03*
Y146482D03*
X236419Y126482D03*
Y106482D03*
X216419Y126482D03*
Y106482D03*
X236419Y146482D03*
X216419D03*
X196419Y186482D03*
Y166482D03*
X197398Y206436D03*
X236419Y186482D03*
Y166482D03*
X216419Y186482D03*
Y166482D03*
X217398Y206436D03*
X197398Y226936D03*
Y246936D03*
Y266936D03*
X217398Y226936D03*
Y246936D03*
Y266936D03*
X197398Y286936D03*
X217398D03*
X228716Y315094D03*
X196289Y302044D03*
X195330Y337964D03*
Y377964D03*
Y357964D03*
X235330Y337964D03*
X215330D03*
X235330Y377964D03*
Y357964D03*
X215330Y377964D03*
Y357964D03*
X196000Y442500D03*
X195330Y417964D03*
X235830Y442464D03*
X235330Y417964D03*
X215830Y442464D03*
X215330Y417964D03*
X179898Y465436D03*
X219898D03*
X199898D03*
X256419Y6482D03*
Y26482D03*
X276419Y6482D03*
Y26482D03*
X256419Y46482D03*
X276419D03*
X256419Y66482D03*
X273500Y66500D03*
X256419Y86482D03*
X274500Y86500D03*
X256419Y126482D03*
X276419D03*
X256419Y106482D03*
X274500Y106500D03*
X256419Y146482D03*
X276419D03*
X237398Y206436D03*
X256419Y186482D03*
X275500Y186500D03*
X251500Y166500D03*
X276419Y166482D03*
X257398Y206436D03*
X277398D03*
X237398Y226936D03*
Y246936D03*
Y266936D03*
X257398Y226936D03*
X277398D03*
X257398Y246936D03*
X277398D03*
X257398Y266936D03*
X277398D03*
X237398Y286936D03*
X257398D03*
X279398D03*
X264680Y317269D03*
X255330Y337964D03*
X275330D03*
X255330Y377964D03*
X275330D03*
X255330Y357964D03*
X275330D03*
X255830Y442464D03*
X275830D03*
X255330Y417964D03*
X275330D03*
X239898Y465436D03*
X279898D03*
X259898D03*
X296419Y6482D03*
Y26482D03*
Y46482D03*
X316419Y6482D03*
Y26482D03*
X336419Y6482D03*
Y26482D03*
X316419Y46482D03*
X336419D03*
X302000Y67000D03*
X301000Y86500D03*
X316419Y66482D03*
X336419D03*
X316419Y86482D03*
X336419D03*
X296419Y126482D03*
X300000Y106500D03*
X296419Y146482D03*
X316419Y126482D03*
X336419D03*
X316419Y106482D03*
X336419D03*
X316419Y146482D03*
X336419D03*
X296419Y186482D03*
X295500Y169000D03*
X297398Y206436D03*
X317500Y186500D03*
X336419Y186482D03*
X317000Y166500D03*
X338500Y166000D03*
X317398Y206436D03*
X337398D03*
X297398Y226936D03*
Y246936D03*
Y266936D03*
X317398Y226936D03*
X337398D03*
X317398Y246936D03*
X337398D03*
X317398Y266936D03*
X337398D03*
X300398Y286936D03*
X317398D03*
X337398D03*
X310990Y310744D03*
X295330Y337964D03*
Y377964D03*
Y357964D03*
X315330Y337964D03*
X335330D03*
X315330Y377964D03*
X335330D03*
X315330Y357964D03*
X335330D03*
X295830Y442464D03*
X295330Y417964D03*
X315830Y442464D03*
X335830D03*
X315330Y417964D03*
X335330D03*
X299898Y465436D03*
X339898D03*
X319898D03*
X356419Y6482D03*
Y26482D03*
Y46482D03*
X376419Y6482D03*
Y26482D03*
X396419Y6482D03*
Y26482D03*
X376419Y46482D03*
X396419D03*
X356419Y66482D03*
Y86482D03*
X376419Y66482D03*
X396419D03*
X376419Y86482D03*
X396419D03*
X356419Y126482D03*
Y106482D03*
Y146482D03*
X376419Y126482D03*
X396419D03*
X376419Y106482D03*
X396419D03*
X376419Y146482D03*
X396419D03*
X357500Y186500D03*
X354500Y166500D03*
X357398Y206436D03*
X376419Y186482D03*
X396419D03*
X380000Y166500D03*
X396419Y166482D03*
X377398Y206436D03*
X397398D03*
X357398Y226936D03*
Y246936D03*
Y266936D03*
X377398Y226936D03*
X397398D03*
X377398Y246936D03*
X397398D03*
X377398Y266936D03*
X397398D03*
X357398Y286936D03*
X377398D03*
X397398D03*
X358093Y312919D03*
X401561Y306394D03*
X355330Y337964D03*
Y377964D03*
Y357964D03*
X375330Y337964D03*
X395330D03*
X375330Y377964D03*
X395330D03*
X375330Y357964D03*
X395330D03*
X355830Y442464D03*
X355330Y417964D03*
X375830Y442464D03*
X395830D03*
X375330Y417964D03*
X395330D03*
X399898Y465436D03*
X379898D03*
X359898D03*
X416419Y6482D03*
Y26482D03*
X436419Y6482D03*
X416419Y46482D03*
X436419D03*
X456419D03*
X416419Y66482D03*
X436419D03*
X456419D03*
X416419Y86482D03*
X436419D03*
X456419D03*
X416419Y126482D03*
X436419D03*
X456419D03*
X416419Y106482D03*
X436419D03*
X456419D03*
X416419Y146482D03*
X436419D03*
X456419D03*
X416500Y166000D03*
X417519Y174482D03*
Y170282D03*
X425919D03*
X421719D03*
Y174482D03*
X431100Y174500D03*
Y170300D03*
X439500D03*
Y174500D03*
X435300Y170300D03*
Y174500D03*
X444100D03*
Y170300D03*
X452500D03*
Y174500D03*
X448300Y170300D03*
Y174500D03*
X457100Y175000D03*
Y170800D03*
X461300D03*
Y175000D03*
X418300Y197500D03*
Y201700D03*
X422500D03*
X426700D03*
X422500Y197500D03*
X426700D03*
X431300D03*
Y201700D03*
X435500D03*
X439700D03*
X435500Y197500D03*
X439700D03*
X444800D03*
Y201700D03*
X449000D03*
X453200D03*
X449000Y197500D03*
X453200D03*
X457800D03*
Y201700D03*
X462000D03*
Y197500D03*
X425919Y174482D03*
X436500Y166000D03*
X456500Y166500D03*
X417398Y206436D03*
X437398D03*
X457398D03*
X417398Y226936D03*
X437398D03*
X457398D03*
X417398Y246936D03*
X437398D03*
X457398D03*
X437398Y266936D03*
X457398D03*
X418398D03*
X437398Y286936D03*
X457398D03*
X418398D03*
X463259Y299869D03*
X439407Y308569D03*
X439585Y321619D03*
X415330Y337964D03*
X435398Y338436D03*
X455398D03*
X415330Y377964D03*
Y357964D03*
X435398Y358436D03*
Y378436D03*
X455398Y358436D03*
Y378436D03*
X435830Y442464D03*
X435330Y417964D03*
X455330D03*
X415830Y442464D03*
X415330Y417964D03*
X454500Y465500D03*
X439898Y465436D03*
X419898D03*
X516419Y6482D03*
X476419Y46482D03*
X496419D03*
X516419D03*
Y66482D03*
X476419D03*
X496419D03*
X516419Y86482D03*
X496419D03*
X476419D03*
Y126482D03*
X516419D03*
X496419D03*
X516419Y106482D03*
X496419D03*
X476419D03*
X485443Y160670D03*
X481243D03*
X493843D03*
X489643D03*
X476419Y146482D03*
X516419D03*
X496419D03*
X519221Y160912D03*
X510821D03*
X506621D03*
X515021D03*
X465500Y170800D03*
Y175000D03*
X466200Y201700D03*
Y197500D03*
X485443Y164870D03*
X481243D03*
X493843D03*
X489643D03*
X477284Y174586D03*
X473084D03*
Y170386D03*
X477284D03*
X498395Y174685D03*
Y170485D03*
X492911Y206602D03*
X488711D03*
X492911Y210802D03*
X488711D03*
X484511D03*
Y206602D03*
X480311Y210802D03*
Y206602D03*
X498052Y200389D03*
Y196189D03*
X477087Y201172D03*
X472887D03*
X477087Y196972D03*
X472887D03*
X519221Y165112D03*
X510821D03*
X506621D03*
X515021D03*
X502595Y174685D03*
Y170485D03*
X506135Y210557D03*
X510335D03*
X514535D03*
X518735D03*
X506135Y206357D03*
X510335D03*
X514535D03*
X518735D03*
X502252Y200389D03*
Y196189D03*
X497398Y226936D03*
X477398D03*
X520898Y228436D03*
X497398Y246936D03*
X477398D03*
Y266936D03*
X512500Y323000D03*
X492000Y321000D03*
X506500Y305500D03*
X520500Y331000D03*
X520381Y300757D03*
X489500Y375500D03*
X485500D03*
X495398Y338436D03*
X475398D03*
X495398Y358436D03*
Y378436D03*
X475398Y358436D03*
Y378436D03*
X477000Y418000D03*
X499000Y418500D03*
X466500Y428000D03*
X533619Y6482D03*
Y26482D03*
Y46482D03*
X550819Y6482D03*
Y26482D03*
Y46482D03*
X568019Y6482D03*
Y26482D03*
Y46482D03*
X573623Y66967D03*
X536419Y66482D03*
X556419D03*
X536419Y86482D03*
X556419D03*
X576419Y106482D03*
Y126482D03*
X536419D03*
X556419D03*
X536419Y106482D03*
X556419D03*
X544476Y161322D03*
X531876D03*
X536076D03*
X540276D03*
X536419Y146482D03*
X556419D03*
X544477Y210389D03*
X544476Y165522D03*
X536076D03*
X531876D03*
X540276D03*
X552924Y175124D03*
X548724D03*
Y170924D03*
X552924D03*
X527711Y175174D03*
X523511D03*
Y170974D03*
X527711D03*
X531877Y210389D03*
X536077D03*
X540277D03*
X531877Y206189D03*
X536077D03*
X540277D03*
X544477D03*
X527761Y200632D03*
X523561D03*
X527761Y196432D03*
X523561D03*
X553171Y200877D03*
X548971D03*
X553171Y196677D03*
X548971D03*
X546600Y257971D03*
X540898Y228436D03*
X561500Y232000D03*
X557000Y231500D03*
X560500Y268000D03*
X548417Y269770D03*
Y262970D03*
X549500Y305500D03*
X543900Y314000D03*
X559996Y282972D03*
X561500Y298000D03*
X534000Y282000D03*
X537136Y326402D03*
X525161Y311000D03*
X577500Y305000D03*
X540736Y309902D03*
X524888Y330228D03*
X537936Y322102D03*
X526270Y338185D03*
X529000Y353500D03*
X548000Y442500D03*
X553000Y425000D03*
X568500Y464841D03*
X538000D03*
X634119Y26482D03*
X585219Y46482D03*
Y26482D03*
Y6482D03*
X602419Y26482D03*
Y6482D03*
X619619D03*
Y26482D03*
Y46482D03*
X634119D03*
Y6482D03*
X602419Y46482D03*
X628500Y104000D03*
X626500Y78500D03*
X611253Y65701D03*
X584543Y86671D03*
X611398Y86936D03*
X633753Y65701D03*
X633898Y86936D03*
X623500Y71500D03*
X634000Y123500D03*
X607000D03*
X616000Y138000D03*
Y115500D03*
X594500Y117000D03*
X616000Y173500D03*
X615500Y199000D03*
X615898Y244436D03*
Y224436D03*
X615398Y266436D03*
X587500Y318500D03*
X600000Y298500D03*
X616498Y316236D03*
X615398Y284436D03*
X633398Y325436D03*
X622598Y331736D03*
X630000Y345500D03*
X600000Y337500D03*
Y342000D03*
X595500D03*
Y337500D03*
X630000Y387500D03*
X612798Y413000D03*
X610898Y425436D03*
Y445436D03*
X617798Y413000D03*
X632898Y404936D03*
Y444936D03*
Y424936D03*
X624898Y400936D03*
X592000Y464841D03*
X610898Y465436D03*
X632898Y464936D03*
G54D40*
X559489Y427559D03*
X603780Y442126D03*
G54D14*
X-25005Y173422D03*
Y133422D03*
Y213422D03*
Y253422D03*
G54D23*
X52705Y352395D03*
X48325Y352450D03*
X57398Y352460D03*
G54D32*
X69491Y365163D03*
X526200Y322000D03*
X533536Y334902D03*
X547700Y419000D03*
G54D41*
X571496Y433071D03*
X581339D03*
X591182D03*
G54D24*
X43159Y377285D03*
X43072Y369247D03*
X51094Y390725D03*
X60052Y390692D03*
X55352Y390774D03*
X538000Y296700D03*
X548000Y432700D03*
G54D15*
X-26505Y124122D03*
Y133422D03*
Y142722D03*
Y204122D03*
Y213422D03*
Y164122D03*
Y173422D03*
Y182722D03*
Y244122D03*
Y253422D03*
Y262722D03*
Y222722D03*
Y283072D03*
G54D33*
X66091Y365163D03*
X522800Y322000D03*
X530136Y334902D03*
X544300Y419000D03*
G54D42*
X607104Y387500D03*
X618566D03*
Y343800D03*
X607104D03*
G54D43*
G01X-4246Y-109426D02*
Y-189426D01*
G01D02*
X1290354D01*
G01X-4246Y-144926D02*
X1290354D01*
G01X-8246Y-93426D02*
G02I-12000J0D01*
G01X-13396D02*
G02I-6850J0D01*
G01X-20246Y-109426D02*
Y-77426D01*
G01X-4246Y-93426D02*
X-36246D01*
G01X-4246Y-109426D02*
X1290354D01*
G01X41309Y387513D02*
X38513D01*
X37500Y386500D01*
G01X45807Y387868D02*
X45452Y387513D01*
X41309D01*
G01X48858Y384817D02*
X45807Y387868D01*
G01X52705Y352345D02*
Y348626D01*
G01X48325Y352400D02*
Y348514D01*
G01X57398Y352410D02*
Y348682D01*
G01X51094Y390775D02*
Y394478D01*
G01X60052Y390742D02*
Y394674D01*
G01X55352Y390824D02*
Y394674D01*
G01X502854Y-109426D02*
Y-189426D01*
G01X522750Y326000D02*
Y326750D01*
X520500Y329000D01*
Y331000D01*
G01X570709Y157637D02*
Y161889D01*
G01D02*
X574961D01*
G01X566457D02*
X570709D01*
G01D02*
Y166141D01*
G01X576457Y161889D02*
X580709D01*
G01X570709Y191889D02*
X574961D01*
G01X566457D02*
X570709D01*
G01D02*
Y196141D01*
G01Y187637D02*
Y191889D01*
G01X576457D02*
X580709D01*
G01X570709Y181889D02*
X574961D01*
G01X566457D02*
X570709D01*
G01D02*
Y186141D01*
G01Y177637D02*
Y181889D01*
G01X576457D02*
X580709D01*
G01X570709Y171889D02*
X574961D01*
G01X566457D02*
X570709D01*
G01D02*
Y176141D01*
G01Y167637D02*
Y171889D01*
G01X576457D02*
X580709D01*
G01X542500Y257971D02*
X546600D01*
G01X533686Y326402D02*
X537136D01*
G01X538000Y296750D02*
Y301000D01*
X544000Y307000D01*
Y314000D01*
X543900D01*
G01X580709Y157637D02*
Y161889D01*
G01X590709Y157637D02*
Y161889D01*
G01X600709Y157637D02*
Y161889D01*
G01X580709D02*
X584961D01*
G01X580709D02*
Y166141D01*
G01Y191889D02*
X584961D01*
G01X580709D02*
Y196141D01*
G01Y187637D02*
Y191889D01*
G01Y181889D02*
X584961D01*
G01X580709D02*
Y186141D01*
G01Y177637D02*
Y181889D01*
G01Y171889D02*
X584961D01*
G01X580709D02*
Y176141D01*
G01Y167637D02*
Y171889D01*
G01X590709Y161889D02*
X594961D01*
G01X586457D02*
X590709D01*
G01D02*
Y166141D01*
G01X600709Y161889D02*
X604961D01*
G01X596457D02*
X600709D01*
G01D02*
Y166141D01*
G01X590709Y191889D02*
X594961D01*
G01X586457D02*
X590709D01*
G01D02*
Y196141D01*
G01Y187637D02*
Y191889D01*
G01X600709D02*
X604961D01*
G01X596457D02*
X600709D01*
G01D02*
Y196141D01*
G01Y187637D02*
Y191889D01*
G01X590709Y181889D02*
X594961D01*
G01X586457D02*
X590709D01*
G01D02*
Y186141D01*
G01Y177637D02*
Y181889D01*
G01X600709D02*
X604961D01*
G01X596457D02*
X600709D01*
G01D02*
Y186141D01*
G01Y177637D02*
Y181889D01*
G01X590709Y171889D02*
X594961D01*
G01X586457D02*
X590709D01*
G01D02*
Y176141D01*
G01Y167637D02*
Y171889D01*
G01X600709D02*
X604961D01*
G01X596457D02*
X600709D01*
G01D02*
Y176141D01*
G01Y167637D02*
Y171889D01*
G01X640354Y-109426D02*
Y-189426D01*
G01X755354Y-109426D02*
Y-189426D01*
G01X922854Y-109426D02*
Y-189426D01*
G01X1092854Y-109426D02*
Y-189426D01*
G01X1290354Y-109426D02*
Y-189426D01*
G01X1318354Y-93426D02*
G02I-12000J0D01*
G01X1313204D02*
G02I-6850J0D01*
G01X1306354Y-109426D02*
Y-77426D01*
G01X1322354Y-93426D02*
X1290354D01*
G54D16*
X197Y189819D03*
Y197419D03*
X9297Y189819D03*
Y197419D03*
X472898Y182636D03*
Y190236D03*
X550498Y322336D03*
Y329936D03*
G54D25*
X49902Y379652D03*
X52462D03*
X55022D03*
X57582D03*
Y363352D03*
X55022D03*
X52462D03*
X49902D03*
G54D34*
X67408Y391259D03*
G54D44*
G01X-12610Y302202D02*
X-27555D01*
G01Y327202D02*
X-7102D01*
G01X-6602Y357202D02*
X-27555D01*
G01X525161Y315852D02*
Y311000D01*
G01X617798Y408936D02*
Y413000D01*
G01X612798Y408836D02*
Y413000D01*
G54D26*
X38128Y379932D03*
X45807Y393668D03*
X542500Y274771D03*
X634488Y77603D03*
G54D35*
X475061Y23622D03*
X494746Y448818D03*
G54D17*
X-27555Y332202D03*
Y327202D03*
Y322202D03*
Y317202D03*
Y312202D03*
Y307202D03*
Y302202D03*
Y357202D03*
Y352202D03*
Y347202D03*
Y342202D03*
Y337202D03*
G54D45*
G01X49902Y379652D02*
Y383773D01*
X48858Y384817D01*
G54D18*
X-25005Y283072D03*
G54D27*
X38109Y363133D03*
X542500Y258171D03*
X618000Y71700D03*
X617798Y403136D03*
X612798Y403036D03*
G54D36*
X421500Y192300D03*
Y180700D03*
X435000Y192300D03*
Y180700D03*
X448500Y192300D03*
Y180700D03*
X462000Y192300D03*
Y180700D03*
G54D46*
G01X61898Y358936D02*
X58809D01*
X57582Y360163D01*
Y363352D01*
G54D28*
X51094Y387325D03*
X60052Y387292D03*
X55352Y387374D03*
X43159Y373885D03*
X43072Y365847D03*
X538000Y293300D03*
X548000Y429300D03*
G54D37*
X487625Y198086D03*
Y173286D03*
X512989Y198162D03*
Y173362D03*
X538135Y198177D03*
Y173377D03*
G54D19*
X38128Y374332D03*
X45807Y388068D03*
X542500Y269171D03*
X634488Y72003D03*
G54D47*
G01X121969Y-179426D02*
Y-161926D01*
G01X131139D02*
Y-179426D01*
G01Y-170676D02*
X121969D01*
G01X144054Y-179426D02*
X142744Y-179134D01*
X141434Y-177968D01*
X140560Y-175926D01*
X140124Y-173593D01*
X140560Y-171259D01*
X141434Y-169218D01*
X142744Y-168051D01*
X144054Y-167760D01*
X145364Y-168051D01*
X146674Y-169218D01*
X147547Y-171259D01*
X147766Y-173593D01*
X147547Y-175926D01*
X146674Y-177968D01*
X145364Y-179134D01*
X144054Y-179426D01*
G01X157842D02*
Y-167760D01*
G01Y-170676D02*
X158716Y-169218D01*
X160026Y-168051D01*
X161772Y-167760D01*
X163300Y-168051D01*
X164611Y-169218D01*
X165266Y-171259D01*
Y-179426D01*
G01X175779Y-171551D02*
X182766D01*
X182111Y-169509D01*
X181019Y-168343D01*
X179491Y-167760D01*
X177962Y-168051D01*
X176652Y-168926D01*
X175779Y-170968D01*
X175342Y-172718D01*
Y-174468D01*
X175779Y-176218D01*
X176871Y-177968D01*
X178181Y-179134D01*
X179709Y-179426D01*
X181237Y-178843D01*
X182766Y-177093D01*
G01X191969Y-184676D02*
X193279Y-185259D01*
X195026Y-184676D01*
X196117Y-183510D01*
X196991Y-182051D01*
X198300Y-177385D01*
X201139Y-167760D01*
G01X194152D02*
X198300Y-177385D01*
G01X233300Y-170093D02*
X234174Y-169218D01*
X234829Y-167760D01*
X235266Y-165717D01*
X234829Y-163968D01*
X233956Y-162801D01*
X232427Y-161926D01*
X226532D01*
Y-179426D01*
X233737D01*
X235266Y-178260D01*
X236139Y-176509D01*
X236576Y-174468D01*
X236139Y-172426D01*
X234829Y-170676D01*
X233300Y-170093D01*
X226532D01*
G01X252984Y-179426D02*
Y-167760D01*
G01Y-169801D02*
X252111Y-168635D01*
X250800Y-168051D01*
X249272Y-167760D01*
X247744Y-168343D01*
X246434Y-169509D01*
X245560Y-171259D01*
X245124Y-173593D01*
X245560Y-175926D01*
X246434Y-177676D01*
X247744Y-178843D01*
X249272Y-179426D01*
X250800Y-179134D01*
X252111Y-178260D01*
X252984Y-177093D01*
G01X270484Y-161926D02*
Y-179426D01*
G01Y-176802D02*
X269611Y-178260D01*
X268300Y-179134D01*
X266772Y-179426D01*
X265026Y-178843D01*
X263716Y-177385D01*
X262842Y-175635D01*
X262624Y-173593D01*
X262842Y-171551D01*
X263716Y-169801D01*
X265026Y-168343D01*
X266772Y-167760D01*
X268300Y-168051D01*
X269392Y-168635D01*
X270484Y-169801D01*
G01X280997Y-183801D02*
X282526Y-184968D01*
X284272Y-185259D01*
X285800Y-184968D01*
X287111Y-183510D01*
X287984Y-181468D01*
Y-167760D01*
G01Y-170093D02*
X287111Y-168926D01*
X285800Y-168051D01*
X284272Y-167760D01*
X282526Y-168343D01*
X281434Y-169509D01*
X280560Y-171551D01*
X280124Y-173593D01*
X280342Y-175343D01*
X281216Y-177385D01*
X282526Y-178843D01*
X284272Y-179426D01*
X285582Y-179134D01*
X287111Y-177968D01*
X287984Y-176802D01*
G01X298279Y-171551D02*
X305266D01*
X304611Y-169509D01*
X303519Y-168343D01*
X301991Y-167760D01*
X300462Y-168051D01*
X299152Y-168926D01*
X298279Y-170968D01*
X297842Y-172718D01*
Y-174468D01*
X298279Y-176218D01*
X299371Y-177968D01*
X300681Y-179134D01*
X302209Y-179426D01*
X303737Y-178843D01*
X305266Y-177093D01*
G01X315997Y-179426D02*
Y-167760D01*
G01Y-170093D02*
X317089Y-168926D01*
X318181Y-168051D01*
X319709Y-167760D01*
X320800Y-168051D01*
X322111Y-168926D01*
G01X349687Y-179426D02*
Y-161926D01*
X354927D01*
X356674Y-162801D01*
X357984Y-164843D01*
X358421Y-167176D01*
X357984Y-169509D01*
X356892Y-171259D01*
X354927Y-172135D01*
X349687D01*
G01X371554Y-161926D02*
Y-179426D01*
G01X366532Y-161926D02*
X376576D01*
G01X390800Y-170093D02*
X391674Y-169218D01*
X392329Y-167760D01*
X392766Y-165717D01*
X392329Y-163968D01*
X391456Y-162801D01*
X389927Y-161926D01*
X384032D01*
Y-179426D01*
X391237D01*
X392766Y-178260D01*
X393639Y-176509D01*
X394076Y-174468D01*
X393639Y-172426D01*
X392329Y-170676D01*
X390800Y-170093D01*
X384032D01*
G01X208377Y-134426D02*
Y-116926D01*
X214054Y-131509D01*
X219731Y-116926D01*
Y-134426D01*
G01X231554D02*
X230244Y-134134D01*
X228934Y-132968D01*
X228060Y-130926D01*
X227624Y-128593D01*
X228060Y-126259D01*
X228934Y-124218D01*
X230244Y-123051D01*
X231554Y-122760D01*
X232864Y-123051D01*
X234174Y-124218D01*
X235047Y-126259D01*
X235266Y-128593D01*
X235047Y-130926D01*
X234174Y-132968D01*
X232864Y-134134D01*
X231554Y-134426D01*
G01X252984Y-116926D02*
Y-134426D01*
G01Y-131802D02*
X252111Y-133260D01*
X250800Y-134134D01*
X249272Y-134426D01*
X247526Y-133843D01*
X246216Y-132385D01*
X245342Y-130635D01*
X245124Y-128593D01*
X245342Y-126551D01*
X246216Y-124801D01*
X247526Y-123343D01*
X249272Y-122760D01*
X250800Y-123051D01*
X251892Y-123635D01*
X252984Y-124801D01*
G01X263279Y-126551D02*
X270266D01*
X269611Y-124509D01*
X268519Y-123343D01*
X266991Y-122760D01*
X265462Y-123051D01*
X264152Y-123926D01*
X263279Y-125968D01*
X262842Y-127718D01*
Y-129468D01*
X263279Y-131218D01*
X264371Y-132968D01*
X265681Y-134134D01*
X267209Y-134426D01*
X268737Y-133843D01*
X270266Y-132093D01*
G01X284054Y-134426D02*
Y-116926D01*
G01X536554Y-179426D02*
Y-161926D01*
X533934Y-165426D01*
G01Y-179426D02*
X539174D01*
G01X556674D02*
Y-161926D01*
X548595Y-174468D01*
X559513D01*
G01X567406Y-172135D02*
X568934Y-170093D01*
X570244Y-168926D01*
X571991Y-168343D01*
X573519Y-168926D01*
X574611Y-170093D01*
X575484Y-171843D01*
X575702Y-173884D01*
X575484Y-175635D01*
X574611Y-177385D01*
X573300Y-178843D01*
X571772Y-179426D01*
X570026Y-178843D01*
X568497Y-177093D01*
X567624Y-174468D01*
X567406Y-171551D01*
X567842Y-167760D01*
X568497Y-165717D01*
X569589Y-163676D01*
X571117Y-162218D01*
X572646Y-161926D01*
X574174Y-162509D01*
X575266Y-163968D01*
G01X584906Y-164843D02*
X586216Y-163093D01*
X587744Y-162218D01*
X589491Y-161926D01*
X591674Y-162509D01*
X593202Y-163968D01*
X593639Y-165717D01*
X593421Y-167468D01*
X592547Y-168926D01*
X588181Y-171843D01*
X586216Y-173884D01*
X584906Y-176802D01*
X584469Y-179426D01*
X593639D01*
G01X602842Y-177385D02*
X604371Y-178843D01*
X606117Y-179426D01*
X607864Y-178843D01*
X609392Y-177093D01*
X610484Y-174468D01*
X610921Y-171843D01*
Y-168635D01*
X610484Y-166010D01*
X609392Y-163676D01*
X608082Y-162509D01*
X606554Y-161926D01*
X604807Y-162509D01*
X603497Y-163676D01*
X602624Y-165426D01*
X602187Y-167760D01*
X602624Y-169801D01*
X603716Y-171843D01*
X605026Y-173010D01*
X606554Y-173301D01*
X608300Y-172718D01*
X609611Y-171259D01*
X610921Y-168635D01*
G01X523437Y-134426D02*
Y-116926D01*
X528677D01*
X530424Y-117801D01*
X531734Y-119843D01*
X532171Y-122176D01*
X531734Y-124509D01*
X530642Y-126259D01*
X528677Y-127135D01*
X523437D01*
G01X550107Y-118385D02*
X548797Y-117509D01*
X547269Y-116926D01*
X545522D01*
X543557Y-117801D01*
X542029Y-119259D01*
X540937Y-121010D01*
X540064Y-123926D01*
X539845Y-126551D01*
X540282Y-129176D01*
X540937Y-130926D01*
X542247Y-132676D01*
X543776Y-133843D01*
X545304Y-134426D01*
X546832D01*
X548361Y-133843D01*
X549671Y-132968D01*
X550763Y-131802D01*
G01X564550Y-125093D02*
X565424Y-124218D01*
X566079Y-122760D01*
X566516Y-120717D01*
X566079Y-118968D01*
X565206Y-117801D01*
X563677Y-116926D01*
X557782D01*
Y-134426D01*
X564987D01*
X566516Y-133260D01*
X567389Y-131509D01*
X567826Y-129468D01*
X567389Y-127426D01*
X566079Y-125676D01*
X564550Y-125093D01*
X557782D01*
G01X573754Y-140259D02*
X586854D01*
G01X592782Y-134426D02*
Y-116926D01*
X602826Y-134426D01*
Y-116926D01*
G01X615304Y-134426D02*
X613557Y-134134D01*
X612029Y-132968D01*
X610719Y-131218D01*
X609845Y-129176D01*
X609409Y-126843D01*
Y-124509D01*
X609845Y-122176D01*
X610719Y-120134D01*
X612029Y-118385D01*
X613557Y-117218D01*
X615304Y-116926D01*
X617050Y-117218D01*
X618579Y-118385D01*
X619889Y-120134D01*
X620763Y-122176D01*
X621199Y-124509D01*
Y-126843D01*
X620763Y-129176D01*
X619889Y-131218D01*
X618579Y-132968D01*
X617050Y-134134D01*
X615304Y-134426D01*
G01X689104Y-179426D02*
Y-161926D01*
X686484Y-165426D01*
G01Y-179426D02*
X691724D01*
G01X701145D02*
X706604Y-161926D01*
X712063Y-179426D01*
G01X710097Y-173301D02*
X703110D01*
G01X666145Y-116926D02*
X671604Y-134426D01*
X677063Y-116926D01*
G01X693471Y-134426D02*
X684737D01*
Y-116926D01*
X693471D01*
G01X689977Y-125384D02*
X684737D01*
G01X702237Y-134426D02*
Y-116926D01*
X707696D01*
X709442Y-117801D01*
X710534Y-118968D01*
X710971Y-121301D01*
X710534Y-123635D01*
X709224Y-125093D01*
X707696Y-125968D01*
X702237D01*
G01X707696D02*
X710971Y-134426D01*
G01X724104Y-135009D02*
X723667Y-134718D01*
Y-134134D01*
X724104Y-133843D01*
X724541Y-134134D01*
Y-134718D01*
X724104Y-135009D01*
G01X790937Y-116926D02*
Y-134426D01*
X799671D01*
G01X816734D02*
Y-122760D01*
G01Y-124801D02*
X815861Y-123635D01*
X814550Y-123051D01*
X813022Y-122760D01*
X811494Y-123343D01*
X810184Y-124509D01*
X809310Y-126259D01*
X808874Y-128593D01*
X809310Y-130926D01*
X810184Y-132676D01*
X811494Y-133843D01*
X813022Y-134426D01*
X814550Y-134134D01*
X815861Y-133260D01*
X816734Y-132093D01*
G01X825719Y-139676D02*
X827029Y-140259D01*
X828776Y-139676D01*
X829867Y-138510D01*
X830741Y-137051D01*
X832050Y-132385D01*
X834889Y-122760D01*
G01X827902D02*
X832050Y-132385D01*
G01X844529Y-126551D02*
X851516D01*
X850861Y-124509D01*
X849769Y-123343D01*
X848241Y-122760D01*
X846712Y-123051D01*
X845402Y-123926D01*
X844529Y-125968D01*
X844092Y-127718D01*
Y-129468D01*
X844529Y-131218D01*
X845621Y-132968D01*
X846931Y-134134D01*
X848459Y-134426D01*
X849987Y-133843D01*
X851516Y-132093D01*
G01X862247Y-134426D02*
Y-122760D01*
G01Y-125093D02*
X863339Y-123926D01*
X864431Y-123051D01*
X865959Y-122760D01*
X867050Y-123051D01*
X868361Y-123926D01*
G01X879529Y-132385D02*
X880621Y-133551D01*
X882149Y-134426D01*
X883459D01*
X884769Y-133843D01*
X885642Y-132968D01*
X886079Y-131802D01*
X885861Y-130051D01*
X884987Y-129176D01*
X881057Y-127426D01*
X880184Y-125384D01*
X880621Y-123926D01*
X881494Y-123051D01*
X882804Y-122760D01*
X884114Y-123051D01*
X885424Y-123926D01*
G01X825937Y-161926D02*
Y-179426D01*
X834671D01*
G01X847804D02*
Y-161926D01*
X845184Y-165426D01*
G01Y-179426D02*
X850424D01*
G01X924737Y-175926D02*
X925829Y-177676D01*
X927139Y-178843D01*
X928667Y-179426D01*
X930414Y-178843D01*
X931724Y-177676D01*
X933034Y-175926D01*
X933471Y-173593D01*
Y-161926D01*
G01X946604Y-179426D02*
X944857Y-179134D01*
X943329Y-177968D01*
X942019Y-176218D01*
X941145Y-174176D01*
X940709Y-171843D01*
Y-169509D01*
X941145Y-167176D01*
X942019Y-165134D01*
X943329Y-163385D01*
X944857Y-162218D01*
X946604Y-161926D01*
X948350Y-162218D01*
X949879Y-163385D01*
X951189Y-165134D01*
X952063Y-167176D01*
X952499Y-169509D01*
Y-171843D01*
X952063Y-174176D01*
X951189Y-176218D01*
X949879Y-177968D01*
X948350Y-179134D01*
X946604Y-179426D01*
G01X959519Y-177093D02*
X961266Y-178551D01*
X963231Y-179426D01*
X964977D01*
X966724Y-178551D01*
X968034Y-177093D01*
X968689Y-175051D01*
X968252Y-173010D01*
X967161Y-171259D01*
X965196Y-170093D01*
X962576Y-169509D01*
X961047Y-168343D01*
X960392Y-166301D01*
X960829Y-164259D01*
X961921Y-162801D01*
X963449Y-161926D01*
X964977D01*
X966506Y-162509D01*
X967816Y-163968D01*
G01X985971Y-179426D02*
X977237D01*
Y-161926D01*
X985971D01*
G01X982477Y-170384D02*
X977237D01*
G01X994737Y-179426D02*
Y-161926D01*
X999977D01*
X1001724Y-162801D01*
X1003034Y-164843D01*
X1003471Y-167176D01*
X1003034Y-169509D01*
X1001942Y-171259D01*
X999977Y-172135D01*
X994737D01*
G01X1012019Y-179426D02*
Y-161926D01*
G01X1021189D02*
Y-179426D01*
G01Y-170676D02*
X1012019D01*
G01X1047237Y-161926D02*
Y-179426D01*
X1055971D01*
G01X1063645D02*
X1069104Y-161926D01*
X1074563Y-179426D01*
G01X1072597Y-173301D02*
X1065610D01*
G01X1081801Y-161926D02*
Y-174468D01*
X1082674Y-177093D01*
X1084421Y-178843D01*
X1086604Y-179426D01*
X1088787Y-178843D01*
X1090534Y-177093D01*
X1091407Y-174468D01*
Y-161926D01*
G01X941801Y-134426D02*
Y-116926D01*
X946167D01*
X947914Y-117801D01*
X949224Y-118968D01*
X950316Y-120717D01*
X951189Y-122760D01*
X951407Y-125676D01*
X951189Y-128593D01*
X950316Y-130635D01*
X949224Y-132385D01*
X947914Y-133551D01*
X946167Y-134426D01*
X941801D01*
G01X960829Y-126551D02*
X967816D01*
X967161Y-124509D01*
X966069Y-123343D01*
X964541Y-122760D01*
X963012Y-123051D01*
X961702Y-123926D01*
X960829Y-125968D01*
X960392Y-127718D01*
Y-129468D01*
X960829Y-131218D01*
X961921Y-132968D01*
X963231Y-134134D01*
X964759Y-134426D01*
X966287Y-133843D01*
X967816Y-132093D01*
G01X978329Y-132385D02*
X979421Y-133551D01*
X980949Y-134426D01*
X982259D01*
X983569Y-133843D01*
X984442Y-132968D01*
X984879Y-131802D01*
X984661Y-130051D01*
X983787Y-129176D01*
X979857Y-127426D01*
X978984Y-125384D01*
X979421Y-123926D01*
X980294Y-123051D01*
X981604Y-122760D01*
X982914Y-123051D01*
X984224Y-123926D01*
G01X999104Y-122760D02*
Y-134426D01*
G01Y-118093D02*
X998667Y-117801D01*
Y-117218D01*
X999104Y-116926D01*
X999541Y-117218D01*
Y-117801D01*
X999104Y-118093D01*
G01X1013547Y-138801D02*
X1015076Y-139968D01*
X1016822Y-140259D01*
X1018350Y-139968D01*
X1019661Y-138510D01*
X1020534Y-136468D01*
Y-122760D01*
G01Y-125093D02*
X1019661Y-123926D01*
X1018350Y-123051D01*
X1016822Y-122760D01*
X1015076Y-123343D01*
X1013984Y-124509D01*
X1013110Y-126551D01*
X1012674Y-128593D01*
X1012892Y-130343D01*
X1013766Y-132385D01*
X1015076Y-133843D01*
X1016822Y-134426D01*
X1018132Y-134134D01*
X1019661Y-132968D01*
X1020534Y-131802D01*
G01X1030392Y-134426D02*
Y-122760D01*
G01Y-125676D02*
X1031266Y-124218D01*
X1032576Y-123051D01*
X1034322Y-122760D01*
X1035850Y-123051D01*
X1037161Y-124218D01*
X1037816Y-126259D01*
Y-134426D01*
G01X1048329Y-126551D02*
X1055316D01*
X1054661Y-124509D01*
X1053569Y-123343D01*
X1052041Y-122760D01*
X1050512Y-123051D01*
X1049202Y-123926D01*
X1048329Y-125968D01*
X1047892Y-127718D01*
Y-129468D01*
X1048329Y-131218D01*
X1049421Y-132968D01*
X1050731Y-134134D01*
X1052259Y-134426D01*
X1053787Y-133843D01*
X1055316Y-132093D01*
G01X1066047Y-134426D02*
Y-122760D01*
G01Y-125093D02*
X1067139Y-123926D01*
X1068231Y-123051D01*
X1069759Y-122760D01*
X1070850Y-123051D01*
X1072161Y-123926D01*
G01X1112804Y-179426D02*
Y-161926D01*
X1110184Y-165426D01*
G01Y-179426D02*
X1115424D01*
G01X1130304D02*
Y-161926D01*
X1127684Y-165426D01*
G01Y-179426D02*
X1132924D01*
G01X1143874Y-180009D02*
X1151734Y-161926D01*
G01X1161156Y-164843D02*
X1162466Y-163093D01*
X1163994Y-162218D01*
X1165741Y-161926D01*
X1167924Y-162509D01*
X1169452Y-163968D01*
X1169889Y-165717D01*
X1169671Y-167468D01*
X1168797Y-168926D01*
X1164431Y-171843D01*
X1162466Y-173884D01*
X1161156Y-176802D01*
X1160719Y-179426D01*
X1169889D01*
G01X1178001Y-176802D02*
X1179310Y-178260D01*
X1180839Y-179134D01*
X1182804Y-179426D01*
X1184769Y-178843D01*
X1186297Y-177676D01*
X1187389Y-175635D01*
X1187607Y-173301D01*
X1187171Y-170968D01*
X1186079Y-169509D01*
X1184550Y-168343D01*
X1183022Y-168051D01*
X1181494Y-168343D01*
X1179529Y-169509D01*
X1180184Y-161926D01*
X1186079D01*
G01X1196374Y-180009D02*
X1204234Y-161926D01*
G01X1213656Y-164843D02*
X1214966Y-163093D01*
X1216494Y-162218D01*
X1218241Y-161926D01*
X1220424Y-162509D01*
X1221952Y-163968D01*
X1222389Y-165717D01*
X1222171Y-167468D01*
X1221297Y-168926D01*
X1216931Y-171843D01*
X1214966Y-173884D01*
X1213656Y-176802D01*
X1213219Y-179426D01*
X1222389D01*
G01X1235304Y-161926D02*
X1233557Y-162509D01*
X1232247Y-163968D01*
X1231374Y-165717D01*
X1230719Y-168051D01*
X1230501Y-170676D01*
X1230719Y-173301D01*
X1231374Y-175635D01*
X1232247Y-177385D01*
X1233557Y-178843D01*
X1235304Y-179426D01*
X1237050Y-178843D01*
X1238361Y-177385D01*
X1239234Y-175635D01*
X1239889Y-173301D01*
X1240107Y-170676D01*
X1239889Y-168051D01*
X1239234Y-165717D01*
X1238361Y-163968D01*
X1237050Y-162509D01*
X1235304Y-161926D01*
G01X1252804Y-179426D02*
Y-161926D01*
X1250184Y-165426D01*
G01Y-179426D02*
X1255424D01*
G01X1272924D02*
Y-161926D01*
X1264845Y-174468D01*
X1275763D01*
G01X1160501Y-134426D02*
Y-116926D01*
X1164867D01*
X1166614Y-117801D01*
X1167924Y-118968D01*
X1169016Y-120717D01*
X1169889Y-122760D01*
X1170107Y-125676D01*
X1169889Y-128593D01*
X1169016Y-130635D01*
X1167924Y-132385D01*
X1166614Y-133551D01*
X1164867Y-134426D01*
X1160501D01*
G01X1186734D02*
Y-122760D01*
G01Y-124801D02*
X1185861Y-123635D01*
X1184550Y-123051D01*
X1183022Y-122760D01*
X1181494Y-123343D01*
X1180184Y-124509D01*
X1179310Y-126259D01*
X1178874Y-128593D01*
X1179310Y-130926D01*
X1180184Y-132676D01*
X1181494Y-133843D01*
X1183022Y-134426D01*
X1184550Y-134134D01*
X1185861Y-133260D01*
X1186734Y-132093D01*
G01X1200304Y-116926D02*
Y-134426D01*
G01X1197247Y-122760D02*
X1203361D01*
G01X1214529Y-126551D02*
X1221516D01*
X1220861Y-124509D01*
X1219769Y-123343D01*
X1218241Y-122760D01*
X1216712Y-123051D01*
X1215402Y-123926D01*
X1214529Y-125968D01*
X1214092Y-127718D01*
Y-129468D01*
X1214529Y-131218D01*
X1215621Y-132968D01*
X1216931Y-134134D01*
X1218459Y-134426D01*
X1219987Y-133843D01*
X1221516Y-132093D01*
G54D29*
X38598Y333436D03*
Y337936D03*
X33508Y368932D03*
Y374132D03*
X69498Y369470D03*
X69547Y373979D03*
X69550Y378236D03*
X537733Y268971D03*
Y263971D03*
X533636Y322102D03*
X533536Y330602D03*
X533636Y326402D03*
X526200Y326000D03*
G54D38*
X570709Y161889D03*
X580709D03*
X570709Y214409D03*
X580709D03*
X570709Y204409D03*
X580709D03*
X570709Y191889D03*
X580709D03*
X570709Y181889D03*
X580709D03*
X570709Y171889D03*
X580709D03*
X570709Y244409D03*
X580709D03*
X570709Y276929D03*
X580709D03*
X570709Y266929D03*
X580709D03*
X570709Y256929D03*
X580709D03*
X570709Y234409D03*
X580709D03*
X570709Y224409D03*
X580709D03*
X570709Y286929D03*
X580709D03*
X590709Y161889D03*
X600709D03*
X590709Y214409D03*
X600709D03*
X590709Y204409D03*
X600709D03*
X590709Y191889D03*
X600709D03*
X590709Y181889D03*
X600709D03*
X590709Y171889D03*
X600709D03*
X590709Y244409D03*
X600709D03*
X590709Y276929D03*
X600709D03*
X590709Y266929D03*
X600709D03*
X590709Y256929D03*
X600709D03*
X590709Y234409D03*
X600709D03*
X590709Y224409D03*
X600709D03*
X590709Y286929D03*
X600709D03*
G54D48*
G01X3398Y326936D02*
X3917D01*
X11917Y318936D01*
X95648D01*
X95649Y318937D01*
X98547D01*
X113265Y304219D01*
X135063D01*
G01X-27555Y322202D02*
X-12698D01*
X-11020Y323880D01*
X4498D01*
X11192Y317186D01*
X96373D01*
X96374Y317187D01*
X97822D01*
X112965Y302044D01*
X196289D01*
G01X-27555Y317202D02*
X-15223D01*
X-10295Y322130D01*
X3773D01*
X10467Y315436D01*
X97097D01*
X112664Y299869D01*
X463259D01*
G01X-27555Y332202D02*
X-7202D01*
X-4500Y329500D01*
X3911D01*
X12725Y320686D01*
X94923D01*
X94924Y320687D01*
X99272D01*
X113565Y306394D01*
X401561D01*
G01X-27555Y342202D02*
X-15500D01*
X-13822Y340524D01*
X-5477D01*
X1547Y333500D01*
X4862D01*
X14176Y324186D01*
X93473D01*
X93474Y324187D01*
X100723D01*
X101749Y323161D01*
Y323160D01*
X114165Y310744D01*
X310990D01*
G01X-27555Y337202D02*
X-13702D01*
X-10500Y334000D01*
X-1429D01*
X1071Y331500D01*
X4386D01*
X13450Y322436D01*
X94198D01*
X94199Y322437D01*
X99997D01*
X113865Y308569D01*
X439407D01*
G01X30058Y374132D02*
X27426D01*
X20057Y366763D01*
Y362268D01*
X1494Y343705D01*
G01X30058Y368932D02*
X26052D01*
X23386Y366266D01*
Y361397D01*
X5694Y343705D01*
G01X-27555Y352202D02*
X-16000D01*
X-7822Y344024D01*
X-4024D01*
X2500Y337500D01*
X10053D01*
X18117Y329436D01*
X91298D01*
X91299Y329437D01*
X102898D01*
X115066Y317269D01*
X264680D01*
G01X-27555Y347202D02*
X-16500D01*
X-11572Y342274D01*
X-4751D01*
X2023Y335500D01*
X9577D01*
X17391Y327686D01*
X92023D01*
X92024Y327687D01*
X102173D01*
X114766Y315094D01*
X228716D01*
G01X10000Y332000D02*
X16064Y325936D01*
X92748D01*
X92749Y325937D01*
X101448D01*
X103499Y323886D01*
Y323885D01*
X114465Y312919D01*
X358093D01*
G01X38128Y374132D02*
X33558D01*
G01X43159Y373835D02*
X41810Y372486D01*
X39774D01*
X38128Y374132D01*
G01X33558Y368932D02*
X33559Y368933D01*
X38109D01*
G01D02*
X39612Y370436D01*
X41933D01*
X43072Y369297D01*
G01X51094Y387275D02*
X52462Y385907D01*
Y379652D01*
G01X38648Y333436D02*
X43898D01*
X44691Y332643D01*
X112180D01*
X125379Y319444D01*
X176762D01*
G01X35148Y333436D02*
X28952D01*
X26723Y335665D01*
G01X52705Y355845D02*
Y358444D01*
X52462Y358687D01*
Y363352D01*
G01X48325Y355900D02*
X45263D01*
X43038Y353675D01*
G01X49902Y363352D02*
Y357477D01*
X48325Y355900D01*
G01X60052Y387242D02*
X57582Y384772D01*
Y379652D01*
G01X67408Y391259D02*
X63391Y387242D01*
X60052D01*
G01X57398Y355910D02*
X55022Y358286D01*
Y363352D01*
G01X55352Y387324D02*
Y385741D01*
X55022Y385411D01*
Y379652D01*
G01X38648Y337936D02*
X41876D01*
X45419Y334393D01*
X112905D01*
X125679Y321619D01*
X439585D01*
G01X35148Y337936D02*
X33194D01*
X30923Y335665D01*
G01X66097Y373979D02*
X64842Y372724D01*
X44270D01*
X43159Y373835D01*
G01Y382607D02*
Y377335D01*
G01D02*
X45279Y375215D01*
X51826D01*
X52462Y375851D01*
Y379652D01*
G01X66100Y378236D02*
X62804Y374940D01*
X55701D01*
X55022Y375619D01*
Y379652D01*
G01X66041Y365163D02*
X63405Y367799D01*
X55816D01*
X55022Y367005D01*
Y363352D01*
G01X43072Y360525D02*
Y365797D01*
G01D02*
X45320Y368045D01*
X51447D01*
X52462Y367030D01*
Y363352D01*
G01X43072Y369297D02*
X44259Y370484D01*
X65034D01*
X66048Y369470D01*
G01X28182Y364061D02*
X30227D01*
X33558Y367392D01*
Y368932D01*
G01Y374132D02*
Y375672D01*
X30227Y379003D01*
X28182D01*
G01X69548Y369470D02*
X69549Y369471D01*
X74803D01*
G01X69541Y365163D02*
X69548Y365170D01*
Y369470D01*
G01X69597Y373979D02*
X70790Y372786D01*
X81000D01*
G01X69600Y378236D02*
X69597Y378233D01*
Y373979D01*
G01X66100Y383508D02*
Y378236D01*
G01X66041Y359891D02*
Y365163D01*
G01X534283Y263971D02*
X532995Y265259D01*
X530953D01*
X471326Y324886D01*
X137980D01*
X93395Y369471D01*
X74803D01*
G01X534283Y268971D02*
X532621Y267309D01*
X531803D01*
X472176Y326936D01*
X138830D01*
X92980Y372786D01*
X81000D01*
G01X570709Y204409D02*
X565000Y210118D01*
Y232500D01*
X562010Y235490D01*
X539494D01*
X539493Y235491D01*
X536401D01*
X467673Y304219D01*
X135063D01*
G01X590709Y214409D02*
X596500Y220200D01*
Y258000D01*
X593250Y261250D01*
X567000D01*
X556846Y251096D01*
X538121D01*
X469773Y319444D01*
X176762D01*
G01X590709Y234409D02*
X586000Y239118D01*
Y249000D01*
X583750Y251250D01*
X565225D01*
X558216Y244241D01*
X540026D01*
X469173Y315094D01*
X228716D01*
G01X561500Y232000D02*
X559760Y233740D01*
X538769D01*
X538768Y233741D01*
X535676D01*
X467373Y302044D01*
X196289D01*
G01X580709Y224409D02*
X585300Y229000D01*
X591500D01*
X594750Y232250D01*
Y250250D01*
X592000Y253000D01*
X564500D01*
X557491Y245991D01*
X540751D01*
X469473Y317269D01*
X264680D01*
G01X570709Y214409D02*
X575000Y218700D01*
Y228500D01*
X576084Y229584D01*
Y238416D01*
X573759Y240741D01*
X573234D01*
X573233Y240742D01*
X571785D01*
X571784Y240741D01*
X538576D01*
X468573Y310744D01*
X310990D01*
G01X570709Y244409D02*
X562409D01*
X560491Y242491D01*
X539301D01*
X468873Y312919D01*
X358093D01*
G01X570709Y234409D02*
X567877Y237241D01*
X537126D01*
X467973Y306394D01*
X401561D01*
G01X557000Y231500D02*
X556510Y231990D01*
X534952D01*
X467073Y299869D01*
X463259D01*
G01X570709Y224409D02*
Y226684D01*
X574334Y230309D01*
Y237166D01*
X572509Y238991D01*
X537851D01*
X468273Y308569D01*
X439407D01*
G01X600709Y244409D02*
X604500Y248200D01*
Y260500D01*
X602000Y263000D01*
X565500D01*
X555346Y252846D01*
X538846D01*
X470073Y321619D01*
X439585D01*
G01X548000Y432750D02*
X547950Y432700D01*
X546124D01*
X546074Y432750D01*
X542750D01*
X485500Y375500D01*
G01X548000Y429250D02*
X547950Y429300D01*
X546124D01*
X546074Y429250D01*
X541750D01*
X491039Y378539D01*
Y377039D01*
X489500Y375500D01*
G01X537993Y293257D02*
X605743D01*
X611150Y287850D01*
Y204000D01*
X607650Y200500D01*
X577500D01*
X575500Y202500D01*
Y216000D01*
X577000Y217500D01*
Y227500D01*
X580000Y230500D01*
X584000D01*
X585500Y232000D01*
Y237000D01*
X583500Y239000D01*
X579000D01*
X573591Y244409D01*
X570709D01*
G01X537783Y268971D02*
X542500D01*
G01D02*
X543299Y269770D01*
X548417D01*
G01X537783Y263971D02*
X542500D01*
G01D02*
X543501Y262970D01*
X548417D01*
G01X600709Y204409D02*
X609100Y212800D01*
Y268400D01*
X604500Y273000D01*
X557500D01*
X554270Y269770D01*
X548417D01*
G01X600709Y224409D02*
X607050Y230750D01*
Y267450D01*
X603550Y270950D01*
X558450D01*
X550470Y262970D01*
X548417D01*
G01X530086Y330602D02*
Y334902D01*
G01X530186Y326402D02*
Y328293D01*
X530086Y328393D01*
Y330602D01*
G01X530186Y322102D02*
Y326402D01*
G01X526250Y326000D02*
Y322000D01*
G01X524888Y330228D02*
X526250Y328866D01*
Y326000D01*
G01X537936Y322102D02*
X533686D01*
G01D02*
X532911Y321327D01*
Y315852D01*
G01X533586Y330602D02*
X538336D01*
X540736Y328202D01*
Y309902D01*
G01X522750Y322000D02*
X522000Y321250D01*
Y308838D01*
X530081Y300757D01*
X532886D01*
G01X526250Y322000D02*
X529036Y319214D01*
Y308352D01*
G01X537993Y293257D02*
X538000Y293250D01*
G01X529011Y293257D02*
X537993D01*
G01X532886Y300757D02*
X540736Y308607D01*
Y309902D01*
G01X530086Y334902D02*
X526803Y338185D01*
X526270D01*
G01X571496Y433071D02*
Y424496D01*
X566000Y419000D01*
X547750D01*
G01X581339Y433071D02*
X577160Y437250D01*
X558250D01*
X550300Y429300D01*
X548050D01*
X548000Y429250D01*
G01X591182Y433071D02*
X587806D01*
X581877Y439000D01*
X557500D01*
X551250Y432750D01*
X549926D01*
X549876Y432700D01*
X548050D01*
X548000Y432750D01*
G01X634488Y71803D02*
X628803D01*
X628500Y71500D01*
X623500D01*
G01X618000D02*
X623500D01*
G54D39*
X529036Y308352D03*
X525161Y315852D03*
X532911D03*
X529011Y293257D03*
X532886Y300757D03*
X525136D03*
M02*
